# T6G (Grand Teton) — schematic netlist excerpt (pin names and nets, part order shuffled) for the footprints in the layout excerpt that follows; sources: Cadence DE-HDL packaged netlist, KiCad conversion of 04192023_DAF0TMB3IC0_F0TG_MB_C_brd_V02_OCP.brd

R3482  Q_RES  33.2 1% CHIP  pkg 0402LF  page 81 : A = GPU_FPGA_BOOT_EN_R ; B = GPU_FPGA_BOOT_EN
R897  Q_RES  0 5% EMPTY  pkg 0402LF  page 356 : A = P1V8_CPU1_RT_1D ; B = P1V8_CPU1_RT3_1A_1D

(kicad_pcb
	(version 20260206)
	(generator "pcbnew")
	(generator_version "10.0")
	(general
		(thickness 1.6)
		(legacy_teardrops no)
	)
	(paper "A4")
	(title_block
		(title "04192023_DAF0TMB3IC0_F0TG_MB_C_brd_V02_OCP.brd")
		(comment 1 "Grand Teton / footprints 2804-2805 of 8354")
	)
	(layers
		(0 "F.Cu" signal "TOP")
		(4 "In1.Cu" signal "GND")
		(6 "In2.Cu" signal "IN1")
		(8 "In3.Cu" signal "GND1")
		(10 "In4.Cu" signal "IN2")
		(12 "In5.Cu" signal "GND2")
		(14 "In6.Cu" signal "IN3")
		(16 "In7.Cu" signal "GND3")
		(18 "In8.Cu" signal "VCC")
		(20 "In9.Cu" signal "VCC1")
		(22 "In10.Cu" signal "GND4")
		(24 "In11.Cu" signal "IN4")
		(26 "In12.Cu" signal "GND5")
		(28 "In13.Cu" signal "IN5")
		(30 "In14.Cu" signal "GND6")
		(32 "In15.Cu" signal "IN6")
		(34 "In16.Cu" signal "GND7")
		(2 "B.Cu" signal "BOTTOM")
		(9 "F.Adhes" user "F.Adhesive")
		(11 "B.Adhes" user "B.Adhesive")
		(13 "F.Paste" user "Package Geometry/Pastemask Top")
		(15 "B.Paste" user "Package Geometry/Pastemask Bottom")
		(5 "F.SilkS" user "Ref Des/Silkscreen Top")
		(7 "B.SilkS" user "Ref Des/Silkscreen Bottom")
		(1 "F.Mask" user "Board Geometry/Soldermask Top")
		(3 "B.Mask" user "Board Geometry/Soldermask Bottom")
		(17 "Dwgs.User" user "User.Drawings")
		(19 "Cmts.User" user "User.Comments")
		(21 "Eco1.User" user "User.Eco1")
		(23 "Eco2.User" user "User.Eco2")
		(25 "Edge.Cuts" user "Board Geometry/Outline")
		(27 "Margin" user)
		(31 "F.CrtYd" user "Package Geometry/Place Bound Top")
		(29 "B.CrtYd" user "Package Geometry/Place Bound Bottom")
		(35 "F.Fab" user "Ref Des/Assembly Top")
		(33 "B.Fab" user "Ref Des/Assembly Bottom")
	)
	(footprint ""
		(layer "F.Cu")
		(at 137.762488 -384.10388 180)
		(property "Reference" "R897"
			(at 0 0 180)
			(layer "F.SilkS")
			(hide yes)
			(effects
				(font
					(size 1.27 1.27)
				)
			)
		)
		(property "Value" ""
			(at 0 0 180)
			(layer "F.Fab")
			(effects
				(font
					(size 1.27 1.27)
				)
			)
		)
		(duplicate_pad_numbers_are_jumpers no)
		(fp_line
			(start 0.7874 0.4064)
			(end -0.7874 0.4064)
			(stroke
				(width 0.1524)
				(type default)
			)
			(layer "F.SilkS")
		)
		(fp_line
			(start 0.7874 -0.4064)
			(end 0.7874 0.4064)
			(stroke
				(width 0.1524)
				(type default)
			)
			(layer "F.SilkS")
		)
		(fp_line
			(start -0.7874 0.4064)
			(end -0.7874 -0.4064)
			(stroke
				(width 0.1524)
				(type default)
			)
			(layer "F.SilkS")
		)
		(fp_line
			(start -0.7874 -0.4064)
			(end 0.7874 -0.4064)
			(stroke
				(width 0.1524)
				(type default)
			)
			(layer "F.SilkS")
		)
		(fp_line
			(start 0.67945 0.3048)
			(end 0.120396 0.3048)
			(stroke
				(width 0.1)
				(type default)
			)
			(layer "F.Fab")
		)
		(fp_line
			(start 0.67945 -0.3048)
			(end 0.67945 0.3048)
			(stroke
				(width 0.1)
				(type default)
			)
			(layer "F.Fab")
		)
		(fp_line
			(start 0.12065 -0.2794)
			(end 0.12065 -0.3048)
			(stroke
				(width 0.1)
				(type default)
			)
			(layer "F.Fab")
		)
		(fp_line
			(start 0.12065 -0.3048)
			(end 0.67945 -0.3048)
			(stroke
				(width 0.1)
				(type default)
			)
			(layer "F.Fab")
		)
		(fp_line
			(start 0.120396 0.3048)
			(end 0.120396 0.2794)
			(stroke
				(width 0.1)
				(type default)
			)
			(layer "F.Fab")
		)
		(fp_line
			(start 0.120396 0.2794)
			(end -0.12065 0.2794)
			(stroke
				(width 0.1)
				(type default)
			)
			(layer "F.Fab")
		)
		(fp_line
			(start -0.12065 0.3048)
			(end -0.67945 0.3048)
			(stroke
				(width 0.1)
				(type default)
			)
			(layer "F.Fab")
		)
		(fp_line
			(start -0.12065 0.2794)
			(end -0.12065 0.3048)
			(stroke
				(width 0.1)
				(type default)
			)
			(layer "F.Fab")
		)
		(fp_line
			(start -0.12065 -0.2794)
			(end 0.12065 -0.2794)
			(stroke
				(width 0.1)
				(type default)
			)
			(layer "F.Fab")
		)
		(fp_line
			(start -0.12065 -0.305054)
			(end -0.12065 -0.2794)
			(stroke
				(width 0.1)
				(type default)
			)
			(layer "F.Fab")
		)
		(fp_line
			(start -0.67945 0.3048)
			(end -0.67945 -0.305054)
			(stroke
				(width 0.1)
				(type default)
			)
			(layer "F.Fab")
		)
		(fp_line
			(start -0.67945 -0.305054)
			(end -0.12065 -0.305054)
			(stroke
				(width 0.1)
				(type default)
			)
			(layer "F.Fab")
		)
		(pad "1" smd rect
			(at -0.40005 0)
			(size 0.4572 0.508)
			(layers "F.Cu" "F.Mask" "F.Paste")
			(net "P1V8_CPU1_RT_1D")
		)
		(pad "2" smd rect
			(at 0.40005 0)
			(size 0.4572 0.508)
			(layers "F.Cu" "F.Mask" "F.Paste")
			(net "P1V8_CPU1_RT3_1A_1D")
		)
	)
	(footprint ""
		(layer "F.Cu")
		(at 194.183 -133.568948 90)
		(property "Reference" "R3482"
			(at 0 0 90)
			(layer "F.SilkS")
			(hide yes)
			(effects
				(font
					(size 1.27 1.27)
				)
			)
		)
		(property "Value" ""
			(at 0 0 90)
			(layer "F.Fab")
			(effects
				(font
					(size 1.27 1.27)
				)
			)
		)
		(duplicate_pad_numbers_are_jumpers no)
		(fp_line
			(start 0.7874 -0.4064)
			(end 0.7874 0.4064)
			(stroke
				(width 0.1524)
				(type default)
			)
			(layer "F.SilkS")
		)
		(fp_line
			(start -0.7874 -0.4064)
			(end 0.7874 -0.4064)
			(stroke
				(width 0.1524)
				(type default)
			)
			(layer "F.SilkS")
		)
		(fp_line
			(start 0.7874 0.4064)
			(end -0.7874 0.4064)
			(stroke
				(width 0.1524)
				(type default)
			)
			(layer "F.SilkS")
		)
		(fp_line
			(start -0.7874 0.4064)
			(end -0.7874 -0.4064)
			(stroke
				(width 0.1524)
				(type default)
			)
			(layer "F.SilkS")
		)
		(fp_line
			(start -0.12065 -0.305054)
			(end -0.12065 -0.2794)
			(stroke
				(width 0.1)
				(type default)
			)
			(layer "F.Fab")
		)
		(fp_line
			(start -0.67945 -0.305054)
			(end -0.12065 -0.305054)
			(stroke
				(width 0.1)
				(type default)
			)
			(layer "F.Fab")
		)
		(fp_line
			(start 0.67945 -0.3048)
			(end 0.67945 0.3048)
			(stroke
				(width 0.1)
				(type default)
			)
			(layer "F.Fab")
		)
		(fp_line
			(start 0.12065 -0.3048)
			(end 0.67945 -0.3048)
			(stroke
				(width 0.1)
				(type default)
			)
			(layer "F.Fab")
		)
		(fp_line
			(start 0.12065 -0.2794)
			(end 0.12065 -0.3048)
			(stroke
				(width 0.1)
				(type default)
			)
			(layer "F.Fab")
		)
		(fp_line
			(start -0.12065 -0.2794)
			(end 0.12065 -0.2794)
			(stroke
				(width 0.1)
				(type default)
			)
			(layer "F.Fab")
		)
		(fp_line
			(start 0.120396 0.2794)
			(end -0.12065 0.2794)
			(stroke
				(width 0.1)
				(type default)
			)
			(layer "F.Fab")
		)
		(fp_line
			(start -0.12065 0.2794)
			(end -0.12065 0.3048)
			(stroke
				(width 0.1)
				(type default)
			)
			(layer "F.Fab")
		)
		(fp_line
			(start 0.67945 0.3048)
			(end 0.120396 0.3048)
			(stroke
				(width 0.1)
				(type default)
			)
			(layer "F.Fab")
		)
		(fp_line
			(start 0.120396 0.3048)
			(end 0.120396 0.2794)
			(stroke
				(width 0.1)
				(type default)
			)
			(layer "F.Fab")
		)
		(fp_line
			(start -0.12065 0.3048)
			(end -0.67945 0.3048)
			(stroke
				(width 0.1)
				(type default)
			)
			(layer "F.Fab")
		)
		(fp_line
			(start -0.67945 0.3048)
			(end -0.67945 -0.305054)
			(stroke
				(width 0.1)
				(type default)
			)
			(layer "F.Fab")
		)
		(pad "1" smd circle
			(at -0.40005 0 90)
			(size 0 0)
			(layers "F.Cu" "F.Mask" "F.Paste")
			(net "GPU_FPGA_BOOT_EN_R")
		)
		(pad "2" smd circle
			(at 0.40005 0 90)
			(size 0 0)
			(layers "F.Cu" "F.Mask" "F.Paste")
			(net "GPU_FPGA_BOOT_EN")
		)
	)
)
